(kicad_pcb
	(version 20260206)
	(generator "pcbnew")
	(generator_version "10.0")
	(general
		(thickness 1.6)
		(legacy_teardrops no)
	)
	(paper "A4")
	(title_block
		(title "9052_F0T_PDB_Converter_Brick_F_V03_1208_1600_OCP.brd")
		(comment 1 "Grand Teton / footprints 362-368 of 578")
	)
	(layers
		(0 "F.Cu" signal "TOP")
		(4 "In1.Cu" signal "GND")
		(6 "In2.Cu" signal "IN1")
		(8 "In3.Cu" signal "GND1")
		(10 "In4.Cu" signal "VCC")
		(12 "In5.Cu" signal "VCC1")
		(14 "In6.Cu" signal "GND2")
		(16 "In7.Cu" signal "IN2")
		(18 "In8.Cu" signal "GND3")
		(2 "B.Cu" signal "BOTTOM")
		(9 "F.Adhes" user "F.Adhesive")
		(11 "B.Adhes" user "B.Adhesive")
		(13 "F.Paste" user "Package Geometry/Pastemask Top")
		(15 "B.Paste" user "Package Geometry/Pastemask Bottom")
		(5 "F.SilkS" user "Ref Des/Silkscreen Top")
		(7 "B.SilkS" user "Ref Des/Silkscreen Bottom")
		(1 "F.Mask" user "Board Geometry/Soldermask Top")
		(3 "B.Mask" user "Board Geometry/Soldermask Bottom")
		(17 "Dwgs.User" user "User.Drawings")
		(19 "Cmts.User" user "User.Comments")
		(21 "Eco1.User" user "User.Eco1")
		(23 "Eco2.User" user "User.Eco2")
		(25 "Edge.Cuts" user "Board Geometry/Outline")
		(27 "Margin" user)
		(31 "F.CrtYd" user "Package Geometry/Place Bound Top")
		(29 "B.CrtYd" user "Package Geometry/Place Bound Bottom")
		(35 "F.Fab" user "Ref Des/Assembly Top")
		(33 "B.Fab" user "Ref Des/Assembly Bottom")
	)
	(footprint ""
		(layer "B.Cu")
		(at 238.682784 -89.50579 180)
		(property "Reference" "R1"
			(at 0 0 0)
			(layer "B.SilkS")
			(hide yes)
			(effects
				(font
					(size 1.27 1.27)
				)
				(justify mirror)
			)
		)
		(property "Value" ""
			(at 0 0 0)
			(layer "B.Fab")
			(effects
				(font
					(size 1.27 1.27)
				)
				(justify mirror)
			)
		)
		(duplicate_pad_numbers_are_jumpers no)
		(fp_line
			(start 0.7874 0.4064)
			(end 0.7874 -0.4064)
			(stroke
				(width 0.1524)
				(type default)
			)
			(layer "B.SilkS")
		)
		(fp_line
			(start 0.7874 -0.4064)
			(end -0.7874 -0.4064)
			(stroke
				(width 0.1524)
				(type default)
			)
			(layer "B.SilkS")
		)
		(fp_line
			(start -0.7874 0.4064)
			(end 0.7874 0.4064)
			(stroke
				(width 0.1524)
				(type default)
			)
			(layer "B.SilkS")
		)
		(fp_line
			(start -0.7874 -0.4064)
			(end -0.7874 0.4064)
			(stroke
				(width 0.1524)
				(type default)
			)
			(layer "B.SilkS")
		)
		(fp_line
			(start 0.67945 0.3048)
			(end 0.67945 -0.305054)
			(stroke
				(width 0.1)
				(type default)
			)
			(layer "B.Fab")
		)
		(fp_line
			(start 0.67945 -0.305054)
			(end 0.12065 -0.305054)
			(stroke
				(width 0.1)
				(type default)
			)
			(layer "B.Fab")
		)
		(fp_line
			(start 0.12065 0.3048)
			(end 0.67945 0.3048)
			(stroke
				(width 0.1)
				(type default)
			)
			(layer "B.Fab")
		)
		(fp_line
			(start 0.12065 0.2794)
			(end 0.12065 0.3048)
			(stroke
				(width 0.1)
				(type default)
			)
			(layer "B.Fab")
		)
		(fp_line
			(start 0.12065 -0.2794)
			(end -0.12065 -0.2794)
			(stroke
				(width 0.1)
				(type default)
			)
			(layer "B.Fab")
		)
		(fp_line
			(start 0.12065 -0.305054)
			(end 0.12065 -0.2794)
			(stroke
				(width 0.1)
				(type default)
			)
			(layer "B.Fab")
		)
		(fp_line
			(start -0.120396 0.3048)
			(end -0.120396 0.2794)
			(stroke
				(width 0.1)
				(type default)
			)
			(layer "B.Fab")
		)
		(fp_line
			(start -0.120396 0.2794)
			(end 0.12065 0.2794)
			(stroke
				(width 0.1)
				(type default)
			)
			(layer "B.Fab")
		)
		(fp_line
			(start -0.12065 -0.2794)
			(end -0.12065 -0.3048)
			(stroke
				(width 0.1)
				(type default)
			)
			(layer "B.Fab")
		)
		(fp_line
			(start -0.12065 -0.3048)
			(end -0.67945 -0.3048)
			(stroke
				(width 0.1)
				(type default)
			)
			(layer "B.Fab")
		)
		(fp_line
			(start -0.67945 0.3048)
			(end -0.120396 0.3048)
			(stroke
				(width 0.1)
				(type default)
			)
			(layer "B.Fab")
		)
		(fp_line
			(start -0.67945 -0.3048)
			(end -0.67945 0.3048)
			(stroke
				(width 0.1)
				(type default)
			)
			(layer "B.Fab")
		)
		(pad "1" smd circle
			(at 0.40005 0)
			(size 0 0)
			(layers "B.Cu" "B.Mask" "B.Paste")
			(net "SMB_PDB_MISC_SCL_R")
		)
		(pad "2" smd circle
			(at -0.40005 0)
			(size 0 0)
			(layers "B.Cu" "B.Mask" "B.Paste")
			(net "P3V3_AUX")
		)
	)
	(footprint ""
		(layer "B.Cu")
		(at 134.493 -77.597 180)
		(property "Reference" "C52"
			(at 0 0 0)
			(layer "B.SilkS")
			(hide yes)
			(effects
				(font
					(size 1.27 1.27)
				)
				(justify mirror)
			)
		)
		(property "Value" ""
			(at 0 0 0)
			(layer "B.Fab")
			(effects
				(font
					(size 1.27 1.27)
				)
				(justify mirror)
			)
		)
		(duplicate_pad_numbers_are_jumpers no)
		(fp_line
			(start 0.7874 0.4064)
			(end 0.7874 -0.4064)
			(stroke
				(width 0.1524)
				(type default)
			)
			(layer "B.SilkS")
		)
		(fp_line
			(start 0.7874 -0.4064)
			(end -0.7874 -0.4064)
			(stroke
				(width 0.1524)
				(type default)
			)
			(layer "B.SilkS")
		)
		(fp_line
			(start -0.7874 0.4064)
			(end 0.7874 0.4064)
			(stroke
				(width 0.1524)
				(type default)
			)
			(layer "B.SilkS")
		)
		(fp_line
			(start -0.7874 -0.4064)
			(end -0.7874 0.4064)
			(stroke
				(width 0.1524)
				(type default)
			)
			(layer "B.SilkS")
		)
		(fp_line
			(start 0.67945 0.3048)
			(end 0.67945 -0.305054)
			(stroke
				(width 0.1)
				(type default)
			)
			(layer "B.Fab")
		)
		(fp_line
			(start 0.67945 -0.305054)
			(end 0.12065 -0.305054)
			(stroke
				(width 0.1)
				(type default)
			)
			(layer "B.Fab")
		)
		(fp_line
			(start 0.12065 0.3048)
			(end 0.67945 0.3048)
			(stroke
				(width 0.1)
				(type default)
			)
			(layer "B.Fab")
		)
		(fp_line
			(start 0.12065 0.2794)
			(end 0.12065 0.3048)
			(stroke
				(width 0.1)
				(type default)
			)
			(layer "B.Fab")
		)
		(fp_line
			(start 0.12065 -0.2794)
			(end -0.12065 -0.2794)
			(stroke
				(width 0.1)
				(type default)
			)
			(layer "B.Fab")
		)
		(fp_line
			(start 0.12065 -0.305054)
			(end 0.12065 -0.2794)
			(stroke
				(width 0.1)
				(type default)
			)
			(layer "B.Fab")
		)
		(fp_line
			(start -0.120396 0.3048)
			(end -0.120396 0.2794)
			(stroke
				(width 0.1)
				(type default)
			)
			(layer "B.Fab")
		)
		(fp_line
			(start -0.120396 0.2794)
			(end 0.12065 0.2794)
			(stroke
				(width 0.1)
				(type default)
			)
			(layer "B.Fab")
		)
		(fp_line
			(start -0.12065 -0.2794)
			(end -0.12065 -0.3048)
			(stroke
				(width 0.1)
				(type default)
			)
			(layer "B.Fab")
		)
		(fp_line
			(start -0.12065 -0.3048)
			(end -0.67945 -0.3048)
			(stroke
				(width 0.1)
				(type default)
			)
			(layer "B.Fab")
		)
		(fp_line
			(start -0.67945 0.3048)
			(end -0.120396 0.3048)
			(stroke
				(width 0.1)
				(type default)
			)
			(layer "B.Fab")
		)
		(fp_line
			(start -0.67945 -0.3048)
			(end -0.67945 0.3048)
			(stroke
				(width 0.1)
				(type default)
			)
			(layer "B.Fab")
		)
		(pad "1" smd circle
			(at 0.40005 0)
			(size 0 0)
			(layers "B.Cu" "B.Mask" "B.Paste")
			(net "SMB_P52V_VPDB_SDA")
		)
		(pad "2" smd circle
			(at -0.40005 0)
			(size 0 0)
			(layers "B.Cu" "B.Mask" "B.Paste")
			(net "GND")
		)
	)
	(footprint ""
		(layer "B.Cu")
		(at 282.067 -30.734 90)
		(property "Reference" "R5915"
			(at 0 0 90)
			(layer "B.SilkS")
			(hide yes)
			(effects
				(font
					(size 1.27 1.27)
				)
				(justify mirror)
			)
		)
		(property "Value" ""
			(at 0 0 90)
			(layer "B.Fab")
			(effects
				(font
					(size 1.27 1.27)
				)
				(justify mirror)
			)
		)
		(duplicate_pad_numbers_are_jumpers no)
		(fp_line
			(start 1.651 -0.8382)
			(end -1.651 -0.8382)
			(stroke
				(width 0.1524)
				(type default)
			)
			(layer "B.SilkS")
		)
		(fp_line
			(start -1.651 -0.8382)
			(end -1.651 0.8382)
			(stroke
				(width 0.1524)
				(type default)
			)
			(layer "B.SilkS")
		)
		(fp_line
			(start 1.651 0.8382)
			(end 1.651 -0.8382)
			(stroke
				(width 0.1524)
				(type default)
			)
			(layer "B.SilkS")
		)
		(fp_line
			(start -1.651 0.8382)
			(end 1.651 0.8382)
			(stroke
				(width 0.1524)
				(type default)
			)
			(layer "B.SilkS")
		)
		(fp_line
			(start 1.559814 -0.7366)
			(end 1.559814 0.7366)
			(stroke
				(width 0.1)
				(type default)
			)
			(layer "B.Fab")
		)
		(fp_line
			(start 1.524 -0.7366)
			(end 1.559814 -0.7366)
			(stroke
				(width 0.1)
				(type default)
			)
			(layer "B.Fab")
		)
		(fp_line
			(start -1.524 -0.7366)
			(end 1.524 -0.7366)
			(stroke
				(width 0.1)
				(type default)
			)
			(layer "B.Fab")
		)
		(fp_line
			(start -1.560576 -0.7366)
			(end -1.524 -0.7366)
			(stroke
				(width 0.1)
				(type default)
			)
			(layer "B.Fab")
		)
		(fp_line
			(start 1.559814 0.7366)
			(end 1.524 0.7366)
			(stroke
				(width 0.1)
				(type default)
			)
			(layer "B.Fab")
		)
		(fp_line
			(start 1.524 0.7366)
			(end -1.524 0.7366)
			(stroke
				(width 0.1)
				(type default)
			)
			(layer "B.Fab")
		)
		(fp_line
			(start -1.524 0.7366)
			(end -1.560576 0.7366)
			(stroke
				(width 0.1)
				(type default)
			)
			(layer "B.Fab")
		)
		(fp_line
			(start -1.560576 0.7366)
			(end -1.560576 -0.7366)
			(stroke
				(width 0.1)
				(type default)
			)
			(layer "B.Fab")
		)
		(pad "1" smd rect
			(at 0.94996 0 90)
			(size 1.1176 1.3716)
			(layers "B.Cu" "B.Mask" "B.Paste")
			(net "P52V_1_R")
		)
		(pad "2" smd rect
			(at -0.94996 0 90)
			(size 1.1176 1.3716)
			(layers "B.Cu" "B.Mask" "B.Paste")
			(net "FM_AC_PWR_CYCLE_BUF")
		)
	)
	(footprint ""
		(layer "B.Cu")
		(at 272.669 -47.625 -90)
		(property "Reference" "R5908"
			(at 0 0 90)
			(layer "B.SilkS")
			(hide yes)
			(effects
				(font
					(size 1.27 1.27)
				)
				(justify mirror)
			)
		)
		(property "Value" ""
			(at 0 0 90)
			(layer "B.Fab")
			(effects
				(font
					(size 1.27 1.27)
				)
				(justify mirror)
			)
		)
		(duplicate_pad_numbers_are_jumpers no)
		(fp_line
			(start -0.7874 0.4064)
			(end 0.7874 0.4064)
			(stroke
				(width 0.1524)
				(type default)
			)
			(layer "B.SilkS")
		)
		(fp_line
			(start 0.7874 0.4064)
			(end 0.7874 -0.4064)
			(stroke
				(width 0.1524)
				(type default)
			)
			(layer "B.SilkS")
		)
		(fp_line
			(start -0.7874 -0.4064)
			(end -0.7874 0.4064)
			(stroke
				(width 0.1524)
				(type default)
			)
			(layer "B.SilkS")
		)
		(fp_line
			(start 0.7874 -0.4064)
			(end -0.7874 -0.4064)
			(stroke
				(width 0.1524)
				(type default)
			)
			(layer "B.SilkS")
		)
		(fp_line
			(start -0.67945 0.3048)
			(end -0.120396 0.3048)
			(stroke
				(width 0.1)
				(type default)
			)
			(layer "B.Fab")
		)
		(fp_line
			(start -0.120396 0.3048)
			(end -0.120396 0.2794)
			(stroke
				(width 0.1)
				(type default)
			)
			(layer "B.Fab")
		)
		(fp_line
			(start 0.12065 0.3048)
			(end 0.67945 0.3048)
			(stroke
				(width 0.1)
				(type default)
			)
			(layer "B.Fab")
		)
		(fp_line
			(start 0.67945 0.3048)
			(end 0.67945 -0.305054)
			(stroke
				(width 0.1)
				(type default)
			)
			(layer "B.Fab")
		)
		(fp_line
			(start -0.120396 0.2794)
			(end 0.12065 0.2794)
			(stroke
				(width 0.1)
				(type default)
			)
			(layer "B.Fab")
		)
		(fp_line
			(start 0.12065 0.2794)
			(end 0.12065 0.3048)
			(stroke
				(width 0.1)
				(type default)
			)
			(layer "B.Fab")
		)
		(fp_line
			(start -0.12065 -0.2794)
			(end -0.12065 -0.3048)
			(stroke
				(width 0.1)
				(type default)
			)
			(layer "B.Fab")
		)
		(fp_line
			(start 0.12065 -0.2794)
			(end -0.12065 -0.2794)
			(stroke
				(width 0.1)
				(type default)
			)
			(layer "B.Fab")
		)
		(fp_line
			(start -0.67945 -0.3048)
			(end -0.67945 0.3048)
			(stroke
				(width 0.1)
				(type default)
			)
			(layer "B.Fab")
		)
		(fp_line
			(start -0.12065 -0.3048)
			(end -0.67945 -0.3048)
			(stroke
				(width 0.1)
				(type default)
			)
			(layer "B.Fab")
		)
		(fp_line
			(start 0.12065 -0.305054)
			(end 0.12065 -0.2794)
			(stroke
				(width 0.1)
				(type default)
			)
			(layer "B.Fab")
		)
		(fp_line
			(start 0.67945 -0.305054)
			(end 0.12065 -0.305054)
			(stroke
				(width 0.1)
				(type default)
			)
			(layer "B.Fab")
		)
		(pad "1" smd circle
			(at 0.40005 0 90)
			(size 0 0)
			(layers "B.Cu" "B.Mask" "B.Paste")
			(net "P52V_HS1_ADR1")
		)
		(pad "2" smd circle
			(at -0.40005 0 90)
			(size 0 0)
			(layers "B.Cu" "B.Mask" "B.Paste")
			(net "GND_FIELD_SIGNAL")
		)
	)
	(footprint ""
		(layer "B.Cu")
		(at 136.779 -77.597 180)
		(property "Reference" "C53"
			(at 0 0 0)
			(layer "B.SilkS")
			(hide yes)
			(effects
				(font
					(size 1.27 1.27)
				)
				(justify mirror)
			)
		)
		(property "Value" ""
			(at 0 0 0)
			(layer "B.Fab")
			(effects
				(font
					(size 1.27 1.27)
				)
				(justify mirror)
			)
		)
		(duplicate_pad_numbers_are_jumpers no)
		(fp_line
			(start 0.7874 0.4064)
			(end 0.7874 -0.4064)
			(stroke
				(width 0.1524)
				(type default)
			)
			(layer "B.SilkS")
		)
		(fp_line
			(start 0.7874 -0.4064)
			(end -0.7874 -0.4064)
			(stroke
				(width 0.1524)
				(type default)
			)
			(layer "B.SilkS")
		)
		(fp_line
			(start -0.7874 0.4064)
			(end 0.7874 0.4064)
			(stroke
				(width 0.1524)
				(type default)
			)
			(layer "B.SilkS")
		)
		(fp_line
			(start -0.7874 -0.4064)
			(end -0.7874 0.4064)
			(stroke
				(width 0.1524)
				(type default)
			)
			(layer "B.SilkS")
		)
		(fp_line
			(start 0.67945 0.3048)
			(end 0.67945 -0.305054)
			(stroke
				(width 0.1)
				(type default)
			)
			(layer "B.Fab")
		)
		(fp_line
			(start 0.67945 -0.305054)
			(end 0.12065 -0.305054)
			(stroke
				(width 0.1)
				(type default)
			)
			(layer "B.Fab")
		)
		(fp_line
			(start 0.12065 0.3048)
			(end 0.67945 0.3048)
			(stroke
				(width 0.1)
				(type default)
			)
			(layer "B.Fab")
		)
		(fp_line
			(start 0.12065 0.2794)
			(end 0.12065 0.3048)
			(stroke
				(width 0.1)
				(type default)
			)
			(layer "B.Fab")
		)
		(fp_line
			(start 0.12065 -0.2794)
			(end -0.12065 -0.2794)
			(stroke
				(width 0.1)
				(type default)
			)
			(layer "B.Fab")
		)
		(fp_line
			(start 0.12065 -0.305054)
			(end 0.12065 -0.2794)
			(stroke
				(width 0.1)
				(type default)
			)
			(layer "B.Fab")
		)
		(fp_line
			(start -0.120396 0.3048)
			(end -0.120396 0.2794)
			(stroke
				(width 0.1)
				(type default)
			)
			(layer "B.Fab")
		)
		(fp_line
			(start -0.120396 0.2794)
			(end 0.12065 0.2794)
			(stroke
				(width 0.1)
				(type default)
			)
			(layer "B.Fab")
		)
		(fp_line
			(start -0.12065 -0.2794)
			(end -0.12065 -0.3048)
			(stroke
				(width 0.1)
				(type default)
			)
			(layer "B.Fab")
		)
		(fp_line
			(start -0.12065 -0.3048)
			(end -0.67945 -0.3048)
			(stroke
				(width 0.1)
				(type default)
			)
			(layer "B.Fab")
		)
		(fp_line
			(start -0.67945 0.3048)
			(end -0.120396 0.3048)
			(stroke
				(width 0.1)
				(type default)
			)
			(layer "B.Fab")
		)
		(fp_line
			(start -0.67945 -0.3048)
			(end -0.67945 0.3048)
			(stroke
				(width 0.1)
				(type default)
			)
			(layer "B.Fab")
		)
		(pad "1" smd circle
			(at 0.40005 0)
			(size 0 0)
			(layers "B.Cu" "B.Mask" "B.Paste")
			(net "P12V_BRICK0_ALERT_N")
		)
		(pad "2" smd circle
			(at -0.40005 0)
			(size 0 0)
			(layers "B.Cu" "B.Mask" "B.Paste")
			(net "GND")
		)
	)
	(footprint ""
		(layer "B.Cu")
		(at 35.56 -105.283)
		(property "Reference" "R5873"
			(at 3.9878 -2.479548 0)
			(unlocked yes)
			(layer "B.SilkS")
			(effects
				(font
					(size 0.7874 0.5842)
					(thickness 0.1524)
				)
				(justify left mirror)
			)
		)
		(property "Value" ""
			(at 0 0 0)
			(layer "B.Fab")
			(effects
				(font
					(size 1.27 1.27)
				)
				(justify mirror)
			)
		)
		(duplicate_pad_numbers_are_jumpers no)
		(fp_line
			(start -4.0386 -1.7526)
			(end -4.0386 1.7526)
			(stroke
				(width 0.1524)
				(type default)
			)
			(layer "B.SilkS")
		)
		(fp_line
			(start -4.0386 1.7526)
			(end 4.0386 1.7526)
			(stroke
				(width 0.1524)
				(type default)
			)
			(layer "B.SilkS")
		)
		(fp_line
			(start 4.0386 -1.7526)
			(end -4.0386 -1.7526)
			(stroke
				(width 0.1524)
				(type default)
			)
			(layer "B.SilkS")
		)
		(fp_line
			(start 4.0386 1.7526)
			(end 4.0386 -1.7526)
			(stroke
				(width 0.1524)
				(type default)
			)
			(layer "B.SilkS")
		)
		(fp_line
			(start -4.0386 -1.7526)
			(end -4.0386 1.7526)
			(stroke
				(width 0.1)
				(type default)
			)
			(layer "B.Fab")
		)
		(fp_line
			(start -4.0386 1.7526)
			(end 4.0386 1.7526)
			(stroke
				(width 0.1)
				(type default)
			)
			(layer "B.Fab")
		)
		(fp_line
			(start 4.0386 -1.7526)
			(end -4.0386 -1.7526)
			(stroke
				(width 0.1)
				(type default)
			)
			(layer "B.Fab")
		)
		(fp_line
			(start 4.0386 1.7526)
			(end 4.0386 -1.7526)
			(stroke
				(width 0.1)
				(type default)
			)
			(layer "B.Fab")
		)
		(pad "1" smd circle
			(at 3.700018 0 270)
			(size 0 0)
			(layers "B.Cu" "B.Mask" "B.Paste")
			(net "P52V_HS")
		)
		(pad "2" smd circle
			(at -3.700018 0 90)
			(size 0 0)
			(layers "B.Cu" "B.Mask" "B.Paste")
			(net "P52V_FAN")
		)
		(pad "3" smd rect
			(at 2.70002 0 90)
			(size 0.4064 1.1176)
			(layers "B.Cu" "B.Mask" "B.Paste")
			(net "P52V_HS")
		)
		(pad "4" smd rect
			(at -2.70002 0 90)
			(size 0.4064 1.1176)
			(layers "B.Cu" "B.Mask" "B.Paste")
			(net "P52V_FAN")
		)
	)
	(footprint ""
		(layer "B.Cu")
		(at 139.065 -77.597 180)
		(property "Reference" "C54"
			(at 0 0 0)
			(layer "B.SilkS")
			(hide yes)
			(effects
				(font
					(size 1.27 1.27)
				)
				(justify mirror)
			)
		)
		(property "Value" ""
			(at 0 0 0)
			(layer "B.Fab")
			(effects
				(font
					(size 1.27 1.27)
				)
				(justify mirror)
			)
		)
		(duplicate_pad_numbers_are_jumpers no)
		(fp_line
			(start 0.7874 0.4064)
			(end 0.7874 -0.4064)
			(stroke
				(width 0.1524)
				(type default)
			)
			(layer "B.SilkS")
		)
		(fp_line
			(start 0.7874 -0.4064)
			(end -0.7874 -0.4064)
			(stroke
				(width 0.1524)
				(type default)
			)
			(layer "B.SilkS")
		)
		(fp_line
			(start -0.7874 0.4064)
			(end 0.7874 0.4064)
			(stroke
				(width 0.1524)
				(type default)
			)
			(layer "B.SilkS")
		)
		(fp_line
			(start -0.7874 -0.4064)
			(end -0.7874 0.4064)
			(stroke
				(width 0.1524)
				(type default)
			)
			(layer "B.SilkS")
		)
		(fp_line
			(start 0.67945 0.3048)
			(end 0.67945 -0.305054)
			(stroke
				(width 0.1)
				(type default)
			)
			(layer "B.Fab")
		)
		(fp_line
			(start 0.67945 -0.305054)
			(end 0.12065 -0.305054)
			(stroke
				(width 0.1)
				(type default)
			)
			(layer "B.Fab")
		)
		(fp_line
			(start 0.12065 0.3048)
			(end 0.67945 0.3048)
			(stroke
				(width 0.1)
				(type default)
			)
			(layer "B.Fab")
		)
		(fp_line
			(start 0.12065 0.2794)
			(end 0.12065 0.3048)
			(stroke
				(width 0.1)
				(type default)
			)
			(layer "B.Fab")
		)
		(fp_line
			(start 0.12065 -0.2794)
			(end -0.12065 -0.2794)
			(stroke
				(width 0.1)
				(type default)
			)
			(layer "B.Fab")
		)
		(fp_line
			(start 0.12065 -0.305054)
			(end 0.12065 -0.2794)
			(stroke
				(width 0.1)
				(type default)
			)
			(layer "B.Fab")
		)
		(fp_line
			(start -0.120396 0.3048)
			(end -0.120396 0.2794)
			(stroke
				(width 0.1)
				(type default)
			)
			(layer "B.Fab")
		)
		(fp_line
			(start -0.120396 0.2794)
			(end 0.12065 0.2794)
			(stroke
				(width 0.1)
				(type default)
			)
			(layer "B.Fab")
		)
		(fp_line
			(start -0.12065 -0.2794)
			(end -0.12065 -0.3048)
			(stroke
				(width 0.1)
				(type default)
			)
			(layer "B.Fab")
		)
		(fp_line
			(start -0.12065 -0.3048)
			(end -0.67945 -0.3048)
			(stroke
				(width 0.1)
				(type default)
			)
			(layer "B.Fab")
		)
		(fp_line
			(start -0.67945 0.3048)
			(end -0.120396 0.3048)
			(stroke
				(width 0.1)
				(type default)
			)
			(layer "B.Fab")
		)
		(fp_line
			(start -0.67945 -0.3048)
			(end -0.67945 0.3048)
			(stroke
				(width 0.1)
				(type default)
			)
			(layer "B.Fab")
		)
		(pad "1" smd circle
			(at 0.40005 0)
			(size 0 0)
			(layers "B.Cu" "B.Mask" "B.Paste")
			(net "SMB_P52V_VPDB_SCL")
		)
		(pad "2" smd circle
			(at -0.40005 0)
			(size 0 0)
			(layers "B.Cu" "B.Mask" "B.Paste")
			(net "GND")
		)
	)
)
